(kicad_pcb
	(version 20260206)
	(generator "pcbnew")
	(generator_version "10.0")
	(general
		(thickness 1.6)
		(legacy_teardrops no)
	)
	(paper "A4")
	(title_block
		(title "01162023_DA0F0TEBIF0_F0T_Expander_BD_F_brd_V02_OCP.brd")
		(comment 1 "Grand Teton / footprints 5364-5369 of 9728")
	)
	(layers
		(0 "F.Cu" signal "TOP")
		(4 "In1.Cu" signal "GND")
		(6 "In2.Cu" signal "VCC")
		(8 "In3.Cu" signal "VCC1")
		(10 "In4.Cu" signal "GND1")
		(12 "In5.Cu" signal "IN1")
		(14 "In6.Cu" signal "GND2")
		(16 "In7.Cu" signal "IN2")
		(18 "In8.Cu" signal "GND3")
		(20 "In9.Cu" signal "IN3")
		(22 "In10.Cu" signal "GND4")
		(24 "In11.Cu" signal "IN4")
		(26 "In12.Cu" signal "GND5")
		(28 "In13.Cu" signal "IN5")
		(30 "In14.Cu" signal "GND6")
		(32 "In15.Cu" signal "IN6")
		(34 "In16.Cu" signal "GND7")
		(2 "B.Cu" signal "BOTTOM")
		(9 "F.Adhes" user "F.Adhesive")
		(11 "B.Adhes" user "B.Adhesive")
		(13 "F.Paste" user "Package Geometry/Pastemask Top")
		(15 "B.Paste" user "Package Geometry/Pastemask Bottom")
		(5 "F.SilkS" user "Ref Des/Silkscreen Top")
		(7 "B.SilkS" user "Ref Des/Silkscreen Bottom")
		(1 "F.Mask" user "Board Geometry/Soldermask Top")
		(3 "B.Mask" user "Board Geometry/Soldermask Bottom")
		(17 "Dwgs.User" user "User.Drawings")
		(19 "Cmts.User" user "User.Comments")
		(21 "Eco1.User" user "User.Eco1")
		(23 "Eco2.User" user "User.Eco2")
		(25 "Edge.Cuts" user "Board Geometry/Outline")
		(27 "Margin" user)
		(31 "F.CrtYd" user "Package Geometry/Place Bound Top")
		(29 "B.CrtYd" user "Package Geometry/Place Bound Bottom")
		(35 "F.Fab" user "Ref Des/Assembly Top")
		(33 "B.Fab" user "Ref Des/Assembly Bottom")
	)
	(footprint ""
		(layer "F.Cu")
		(at 123.648978 -89.53373)
		(property "Reference" "R1587"
			(at 0 0 0)
			(layer "F.SilkS")
			(hide yes)
			(effects
				(font
					(size 1.27 1.27)
				)
			)
		)
		(property "Value" ""
			(at 0 0 0)
			(layer "F.Fab")
			(effects
				(font
					(size 1.27 1.27)
				)
			)
		)
		(duplicate_pad_numbers_are_jumpers no)
		(fp_line
			(start -0.7874 -0.4064)
			(end 0.7874 -0.4064)
			(stroke
				(width 0.1524)
				(type default)
			)
			(layer "F.SilkS")
		)
		(fp_line
			(start -0.7874 0.4064)
			(end -0.7874 -0.4064)
			(stroke
				(width 0.1524)
				(type default)
			)
			(layer "F.SilkS")
		)
		(fp_line
			(start 0.7874 -0.4064)
			(end 0.7874 0.4064)
			(stroke
				(width 0.1524)
				(type default)
			)
			(layer "F.SilkS")
		)
		(fp_line
			(start 0.7874 0.4064)
			(end -0.7874 0.4064)
			(stroke
				(width 0.1524)
				(type default)
			)
			(layer "F.SilkS")
		)
		(fp_line
			(start -0.67945 -0.305054)
			(end -0.12065 -0.305054)
			(stroke
				(width 0.1)
				(type default)
			)
			(layer "F.Fab")
		)
		(fp_line
			(start -0.67945 0.3048)
			(end -0.67945 -0.305054)
			(stroke
				(width 0.1)
				(type default)
			)
			(layer "F.Fab")
		)
		(fp_line
			(start -0.12065 -0.305054)
			(end -0.12065 -0.2794)
			(stroke
				(width 0.1)
				(type default)
			)
			(layer "F.Fab")
		)
		(fp_line
			(start -0.12065 -0.2794)
			(end 0.12065 -0.2794)
			(stroke
				(width 0.1)
				(type default)
			)
			(layer "F.Fab")
		)
		(fp_line
			(start -0.12065 0.2794)
			(end -0.12065 0.3048)
			(stroke
				(width 0.1)
				(type default)
			)
			(layer "F.Fab")
		)
		(fp_line
			(start -0.12065 0.3048)
			(end -0.67945 0.3048)
			(stroke
				(width 0.1)
				(type default)
			)
			(layer "F.Fab")
		)
		(fp_line
			(start 0.120396 0.2794)
			(end -0.12065 0.2794)
			(stroke
				(width 0.1)
				(type default)
			)
			(layer "F.Fab")
		)
		(fp_line
			(start 0.120396 0.3048)
			(end 0.120396 0.2794)
			(stroke
				(width 0.1)
				(type default)
			)
			(layer "F.Fab")
		)
		(fp_line
			(start 0.12065 -0.3048)
			(end 0.67945 -0.3048)
			(stroke
				(width 0.1)
				(type default)
			)
			(layer "F.Fab")
		)
		(fp_line
			(start 0.12065 -0.2794)
			(end 0.12065 -0.3048)
			(stroke
				(width 0.1)
				(type default)
			)
			(layer "F.Fab")
		)
		(fp_line
			(start 0.67945 -0.3048)
			(end 0.67945 0.3048)
			(stroke
				(width 0.1)
				(type default)
			)
			(layer "F.Fab")
		)
		(fp_line
			(start 0.67945 0.3048)
			(end 0.120396 0.3048)
			(stroke
				(width 0.1)
				(type default)
			)
			(layer "F.Fab")
		)
		(pad "1" smd circle
			(at -0.40005 0)
			(size 0 0)
			(layers "F.Cu" "F.Mask" "F.Paste")
			(net "SMB_BIC_I2C9_MUX0_SSD3_R_SDA")
		)
		(pad "2" smd circle
			(at 0.40005 0)
			(size 0 0)
			(layers "F.Cu" "F.Mask" "F.Paste")
			(net "SMB_BIC_I2C9_MUX0_SSD3_SDA")
		)
	)
	(footprint ""
		(layer "F.Cu")
		(at 462.465674 -279.69083 180)
		(property "Reference" "R809"
			(at 0 0 180)
			(layer "F.SilkS")
			(hide yes)
			(effects
				(font
					(size 1.27 1.27)
				)
			)
		)
		(property "Value" ""
			(at 0 0 180)
			(layer "F.Fab")
			(effects
				(font
					(size 1.27 1.27)
				)
			)
		)
		(duplicate_pad_numbers_are_jumpers no)
		(fp_line
			(start 0.7874 0.4064)
			(end -0.7874 0.4064)
			(stroke
				(width 0.1524)
				(type default)
			)
			(layer "F.SilkS")
		)
		(fp_line
			(start 0.7874 -0.4064)
			(end 0.7874 0.4064)
			(stroke
				(width 0.1524)
				(type default)
			)
			(layer "F.SilkS")
		)
		(fp_line
			(start -0.7874 0.4064)
			(end -0.7874 -0.4064)
			(stroke
				(width 0.1524)
				(type default)
			)
			(layer "F.SilkS")
		)
		(fp_line
			(start -0.7874 -0.4064)
			(end 0.7874 -0.4064)
			(stroke
				(width 0.1524)
				(type default)
			)
			(layer "F.SilkS")
		)
		(fp_line
			(start 0.67945 0.3048)
			(end 0.120396 0.3048)
			(stroke
				(width 0.1)
				(type default)
			)
			(layer "F.Fab")
		)
		(fp_line
			(start 0.67945 -0.3048)
			(end 0.67945 0.3048)
			(stroke
				(width 0.1)
				(type default)
			)
			(layer "F.Fab")
		)
		(fp_line
			(start 0.12065 -0.2794)
			(end 0.12065 -0.3048)
			(stroke
				(width 0.1)
				(type default)
			)
			(layer "F.Fab")
		)
		(fp_line
			(start 0.12065 -0.3048)
			(end 0.67945 -0.3048)
			(stroke
				(width 0.1)
				(type default)
			)
			(layer "F.Fab")
		)
		(fp_line
			(start 0.120396 0.3048)
			(end 0.120396 0.2794)
			(stroke
				(width 0.1)
				(type default)
			)
			(layer "F.Fab")
		)
		(fp_line
			(start 0.120396 0.2794)
			(end -0.12065 0.2794)
			(stroke
				(width 0.1)
				(type default)
			)
			(layer "F.Fab")
		)
		(fp_line
			(start -0.12065 0.3048)
			(end -0.67945 0.3048)
			(stroke
				(width 0.1)
				(type default)
			)
			(layer "F.Fab")
		)
		(fp_line
			(start -0.12065 0.2794)
			(end -0.12065 0.3048)
			(stroke
				(width 0.1)
				(type default)
			)
			(layer "F.Fab")
		)
		(fp_line
			(start -0.12065 -0.2794)
			(end 0.12065 -0.2794)
			(stroke
				(width 0.1)
				(type default)
			)
			(layer "F.Fab")
		)
		(fp_line
			(start -0.12065 -0.305054)
			(end -0.12065 -0.2794)
			(stroke
				(width 0.1)
				(type default)
			)
			(layer "F.Fab")
		)
		(fp_line
			(start -0.67945 0.3048)
			(end -0.67945 -0.305054)
			(stroke
				(width 0.1)
				(type default)
			)
			(layer "F.Fab")
		)
		(fp_line
			(start -0.67945 -0.305054)
			(end -0.12065 -0.305054)
			(stroke
				(width 0.1)
				(type default)
			)
			(layer "F.Fab")
		)
		(pad "1" smd circle
			(at -0.40005 0 180)
			(size 0 0)
			(layers "F.Cu" "F.Mask" "F.Paste")
			(net "SMB_BIC_I2C6_MUX_PEX_ADC_R_SDA")
		)
		(pad "2" smd circle
			(at 0.40005 0 180)
			(size 0 0)
			(layers "F.Cu" "F.Mask" "F.Paste")
			(net "SMB_PEX3_P1V25_ADC_SDA")
		)
	)
	(footprint ""
		(layer "F.Cu")
		(at 248.452894 -159.173418 90)
		(property "Reference" "PC799"
			(at 0 0 90)
			(layer "F.SilkS")
			(hide yes)
			(effects
				(font
					(size 1.27 1.27)
				)
			)
		)
		(property "Value" ""
			(at 0 0 90)
			(layer "F.Fab")
			(effects
				(font
					(size 1.27 1.27)
				)
			)
		)
		(duplicate_pad_numbers_are_jumpers no)
		(fp_line
			(start 0.7874 -0.4064)
			(end 0.7874 0.4064)
			(stroke
				(width 0.1524)
				(type default)
			)
			(layer "F.SilkS")
		)
		(fp_line
			(start -0.7874 -0.4064)
			(end 0.7874 -0.4064)
			(stroke
				(width 0.1524)
				(type default)
			)
			(layer "F.SilkS")
		)
		(fp_line
			(start 0.7874 0.4064)
			(end -0.7874 0.4064)
			(stroke
				(width 0.1524)
				(type default)
			)
			(layer "F.SilkS")
		)
		(fp_line
			(start -0.7874 0.4064)
			(end -0.7874 -0.4064)
			(stroke
				(width 0.1524)
				(type default)
			)
			(layer "F.SilkS")
		)
		(fp_line
			(start -0.12065 -0.305054)
			(end -0.12065 -0.2794)
			(stroke
				(width 0.1)
				(type default)
			)
			(layer "F.Fab")
		)
		(fp_line
			(start -0.67945 -0.305054)
			(end -0.12065 -0.305054)
			(stroke
				(width 0.1)
				(type default)
			)
			(layer "F.Fab")
		)
		(fp_line
			(start 0.67945 -0.3048)
			(end 0.67945 0.3048)
			(stroke
				(width 0.1)
				(type default)
			)
			(layer "F.Fab")
		)
		(fp_line
			(start 0.12065 -0.3048)
			(end 0.67945 -0.3048)
			(stroke
				(width 0.1)
				(type default)
			)
			(layer "F.Fab")
		)
		(fp_line
			(start 0.12065 -0.2794)
			(end 0.12065 -0.3048)
			(stroke
				(width 0.1)
				(type default)
			)
			(layer "F.Fab")
		)
		(fp_line
			(start -0.12065 -0.2794)
			(end 0.12065 -0.2794)
			(stroke
				(width 0.1)
				(type default)
			)
			(layer "F.Fab")
		)
		(fp_line
			(start 0.120396 0.2794)
			(end -0.12065 0.2794)
			(stroke
				(width 0.1)
				(type default)
			)
			(layer "F.Fab")
		)
		(fp_line
			(start -0.12065 0.2794)
			(end -0.12065 0.3048)
			(stroke
				(width 0.1)
				(type default)
			)
			(layer "F.Fab")
		)
		(fp_line
			(start 0.67945 0.3048)
			(end 0.120396 0.3048)
			(stroke
				(width 0.1)
				(type default)
			)
			(layer "F.Fab")
		)
		(fp_line
			(start 0.120396 0.3048)
			(end 0.120396 0.2794)
			(stroke
				(width 0.1)
				(type default)
			)
			(layer "F.Fab")
		)
		(fp_line
			(start -0.12065 0.3048)
			(end -0.67945 0.3048)
			(stroke
				(width 0.1)
				(type default)
			)
			(layer "F.Fab")
		)
		(fp_line
			(start -0.67945 0.3048)
			(end -0.67945 -0.305054)
			(stroke
				(width 0.1)
				(type default)
			)
			(layer "F.Fab")
		)
		(pad "1" smd circle
			(at -0.40005 0 90)
			(size 0 0)
			(layers "F.Cu" "F.Mask" "F.Paste")
			(net "P12V_AUX")
		)
		(pad "2" smd circle
			(at 0.40005 0 90)
			(size 0 0)
			(layers "F.Cu" "F.Mask" "F.Paste")
			(net "GND")
		)
	)
	(footprint ""
		(layer "F.Cu")
		(at 134.94639 -184.656984 -90)
		(property "Reference" "R1112"
			(at 0 0 270)
			(layer "F.SilkS")
			(hide yes)
			(effects
				(font
					(size 1.27 1.27)
				)
			)
		)
		(property "Value" ""
			(at 0 0 270)
			(layer "F.Fab")
			(effects
				(font
					(size 1.27 1.27)
				)
			)
		)
		(duplicate_pad_numbers_are_jumpers no)
		(fp_line
			(start -0.7874 -0.4064)
			(end 0.7874 -0.4064)
			(stroke
				(width 0.1524)
				(type default)
			)
			(layer "F.SilkS")
		)
		(fp_line
			(start -0.67945 0.3048)
			(end -0.67945 -0.305054)
			(stroke
				(width 0.1)
				(type default)
			)
			(layer "F.Fab")
		)
		(fp_line
			(start -0.12065 0.3048)
			(end -0.67945 0.3048)
			(stroke
				(width 0.1)
				(type default)
			)
			(layer "F.Fab")
		)
		(fp_line
			(start 0.120396 0.3048)
			(end 0.120396 0.2794)
			(stroke
				(width 0.1)
				(type default)
			)
			(layer "F.Fab")
		)
		(fp_line
			(start 0.67945 0.3048)
			(end 0.120396 0.3048)
			(stroke
				(width 0.1)
				(type default)
			)
			(layer "F.Fab")
		)
		(fp_line
			(start -0.12065 0.2794)
			(end -0.12065 0.3048)
			(stroke
				(width 0.1)
				(type default)
			)
			(layer "F.Fab")
		)
		(fp_line
			(start 0.120396 0.2794)
			(end -0.12065 0.2794)
			(stroke
				(width 0.1)
				(type default)
			)
			(layer "F.Fab")
		)
		(fp_line
			(start -0.12065 -0.2794)
			(end 0.12065 -0.2794)
			(stroke
				(width 0.1)
				(type default)
			)
			(layer "F.Fab")
		)
		(fp_line
			(start 0.12065 -0.2794)
			(end 0.12065 -0.3048)
			(stroke
				(width 0.1)
				(type default)
			)
			(layer "F.Fab")
		)
		(fp_line
			(start 0.12065 -0.3048)
			(end 0.67945 -0.3048)
			(stroke
				(width 0.1)
				(type default)
			)
			(layer "F.Fab")
		)
		(fp_line
			(start 0.67945 -0.3048)
			(end 0.67945 0.3048)
			(stroke
				(width 0.1)
				(type default)
			)
			(layer "F.Fab")
		)
		(fp_line
			(start -0.67945 -0.305054)
			(end -0.12065 -0.305054)
			(stroke
				(width 0.1)
				(type default)
			)
			(layer "F.Fab")
		)
		(fp_line
			(start -0.12065 -0.305054)
			(end -0.12065 -0.2794)
			(stroke
				(width 0.1)
				(type default)
			)
			(layer "F.Fab")
		)
		(pad "1" smd circle
			(at -0.40005 0 270)
			(size 0 0)
			(layers "F.Cu" "F.Mask" "F.Paste")
			(net "CLK_100M_DB2000QL_GPU_REF0_R_DP")
		)
		(pad "2" smd circle
			(at 0.40005 0 270)
			(size 0 0)
			(layers "F.Cu" "F.Mask" "F.Paste")
			(net "CLK_100M_DB2000QL_GPU_REF0_DP")
		)
	)
	(footprint ""
		(layer "F.Cu")
		(at 98.048318 -394.1318)
		(property "Reference" "R5458"
			(at 0 0 0)
			(layer "F.SilkS")
			(hide yes)
			(effects
				(font
					(size 1.27 1.27)
				)
			)
		)
		(property "Value" ""
			(at 0 0 0)
			(layer "F.Fab")
			(effects
				(font
					(size 1.27 1.27)
				)
			)
		)
		(duplicate_pad_numbers_are_jumpers no)
		(fp_line
			(start -0.7874 -0.4064)
			(end 0.7874 -0.4064)
			(stroke
				(width 0.1524)
				(type default)
			)
			(layer "F.SilkS")
		)
		(fp_line
			(start -0.7874 0.4064)
			(end -0.7874 -0.4064)
			(stroke
				(width 0.1524)
				(type default)
			)
			(layer "F.SilkS")
		)
		(fp_line
			(start 0.7874 -0.4064)
			(end 0.7874 0.4064)
			(stroke
				(width 0.1524)
				(type default)
			)
			(layer "F.SilkS")
		)
		(fp_line
			(start 0.7874 0.4064)
			(end -0.7874 0.4064)
			(stroke
				(width 0.1524)
				(type default)
			)
			(layer "F.SilkS")
		)
		(fp_line
			(start -0.67945 -0.305054)
			(end -0.12065 -0.305054)
			(stroke
				(width 0.1)
				(type default)
			)
			(layer "F.Fab")
		)
		(fp_line
			(start -0.67945 0.3048)
			(end -0.67945 -0.305054)
			(stroke
				(width 0.1)
				(type default)
			)
			(layer "F.Fab")
		)
		(fp_line
			(start -0.12065 -0.305054)
			(end -0.12065 -0.2794)
			(stroke
				(width 0.1)
				(type default)
			)
			(layer "F.Fab")
		)
		(fp_line
			(start -0.12065 -0.2794)
			(end 0.12065 -0.2794)
			(stroke
				(width 0.1)
				(type default)
			)
			(layer "F.Fab")
		)
		(fp_line
			(start -0.12065 0.2794)
			(end -0.12065 0.3048)
			(stroke
				(width 0.1)
				(type default)
			)
			(layer "F.Fab")
		)
		(fp_line
			(start -0.12065 0.3048)
			(end -0.67945 0.3048)
			(stroke
				(width 0.1)
				(type default)
			)
			(layer "F.Fab")
		)
		(fp_line
			(start 0.120396 0.2794)
			(end -0.12065 0.2794)
			(stroke
				(width 0.1)
				(type default)
			)
			(layer "F.Fab")
		)
		(fp_line
			(start 0.120396 0.3048)
			(end 0.120396 0.2794)
			(stroke
				(width 0.1)
				(type default)
			)
			(layer "F.Fab")
		)
		(fp_line
			(start 0.12065 -0.3048)
			(end 0.67945 -0.3048)
			(stroke
				(width 0.1)
				(type default)
			)
			(layer "F.Fab")
		)
		(fp_line
			(start 0.12065 -0.2794)
			(end 0.12065 -0.3048)
			(stroke
				(width 0.1)
				(type default)
			)
			(layer "F.Fab")
		)
		(fp_line
			(start 0.67945 -0.3048)
			(end 0.67945 0.3048)
			(stroke
				(width 0.1)
				(type default)
			)
			(layer "F.Fab")
		)
		(fp_line
			(start 0.67945 0.3048)
			(end 0.120396 0.3048)
			(stroke
				(width 0.1)
				(type default)
			)
			(layer "F.Fab")
		)
		(pad "1" smd circle
			(at -0.40005 0)
			(size 0 0)
			(layers "F.Cu" "F.Mask" "F.Paste")
			(net "GND")
		)
		(pad "2" smd circle
			(at 0.40005 0)
			(size 0 0)
			(layers "F.Cu" "F.Mask" "F.Paste")
			(net "BIC_USB_HUB_PSELF")
		)
	)
	(footprint ""
		(layer "F.Cu")
		(at 149.586442 -252.356874 -90)
		(property "Reference" "R1286"
			(at 0 0 270)
			(layer "F.SilkS")
			(hide yes)
			(effects
				(font
					(size 1.27 1.27)
				)
			)
		)
		(property "Value" ""
			(at 0 0 270)
			(layer "F.Fab")
			(effects
				(font
					(size 1.27 1.27)
				)
			)
		)
		(duplicate_pad_numbers_are_jumpers no)
		(fp_line
			(start -0.7874 0.4064)
			(end -0.7874 -0.4064)
			(stroke
				(width 0.1524)
				(type default)
			)
			(layer "F.SilkS")
		)
		(fp_line
			(start 0.7874 0.4064)
			(end -0.7874 0.4064)
			(stroke
				(width 0.1524)
				(type default)
			)
			(layer "F.SilkS")
		)
		(fp_line
			(start -0.7874 -0.4064)
			(end 0.7874 -0.4064)
			(stroke
				(width 0.1524)
				(type default)
			)
			(layer "F.SilkS")
		)
		(fp_line
			(start 0.7874 -0.4064)
			(end 0.7874 0.4064)
			(stroke
				(width 0.1524)
				(type default)
			)
			(layer "F.SilkS")
		)
		(fp_line
			(start -0.67945 0.3048)
			(end -0.67945 -0.305054)
			(stroke
				(width 0.1)
				(type default)
			)
			(layer "F.Fab")
		)
		(fp_line
			(start -0.12065 0.3048)
			(end -0.67945 0.3048)
			(stroke
				(width 0.1)
				(type default)
			)
			(layer "F.Fab")
		)
		(fp_line
			(start 0.120396 0.3048)
			(end 0.120396 0.2794)
			(stroke
				(width 0.1)
				(type default)
			)
			(layer "F.Fab")
		)
		(fp_line
			(start 0.67945 0.3048)
			(end 0.120396 0.3048)
			(stroke
				(width 0.1)
				(type default)
			)
			(layer "F.Fab")
		)
		(fp_line
			(start -0.12065 0.2794)
			(end -0.12065 0.3048)
			(stroke
				(width 0.1)
				(type default)
			)
			(layer "F.Fab")
		)
		(fp_line
			(start 0.120396 0.2794)
			(end -0.12065 0.2794)
			(stroke
				(width 0.1)
				(type default)
			)
			(layer "F.Fab")
		)
		(fp_line
			(start -0.12065 -0.2794)
			(end 0.12065 -0.2794)
			(stroke
				(width 0.1)
				(type default)
			)
			(layer "F.Fab")
		)
		(fp_line
			(start 0.12065 -0.2794)
			(end 0.12065 -0.3048)
			(stroke
				(width 0.1)
				(type default)
			)
			(layer "F.Fab")
		)
		(fp_line
			(start 0.12065 -0.3048)
			(end 0.67945 -0.3048)
			(stroke
				(width 0.1)
				(type default)
			)
			(layer "F.Fab")
		)
		(fp_line
			(start 0.67945 -0.3048)
			(end 0.67945 0.3048)
			(stroke
				(width 0.1)
				(type default)
			)
			(layer "F.Fab")
		)
		(fp_line
			(start -0.67945 -0.305054)
			(end -0.12065 -0.305054)
			(stroke
				(width 0.1)
				(type default)
			)
			(layer "F.Fab")
		)
		(fp_line
			(start -0.12065 -0.305054)
			(end -0.12065 -0.2794)
			(stroke
				(width 0.1)
				(type default)
			)
			(layer "F.Fab")
		)
		(pad "1" smd circle
			(at -0.40005 0 270)
			(size 0 0)
			(layers "F.Cu" "F.Mask" "F.Paste")
			(net "GND")
		)
		(pad "2" smd circle
			(at 0.40005 0 270)
			(size 0 0)
			(layers "F.Cu" "F.Mask" "F.Paste")
			(net "PEX1_DBG_MODE2")
		)
	)
)
